(kicad_pcb
	(version 20241229)
	(generator "pcbnew")
	(generator_version "9.0")
	(general
		(thickness 1.62)
		(legacy_teardrops no)
	)
	(paper "A4")
	(title_block
		(title "OCuLink to 10GbE adapter")
		(date "2026-02-23")
		(rev "1.1.0")
		(company "Antmicro Ltd")
		(comment 1 "www.antmicro.com")
		(comment 9 "footprints 429-434 of 510")
	)
	(layers
		(0 "F.Cu" signal)
		(4 "In1.Cu" signal)
		(6 "In2.Cu" signal)
		(8 "In3.Cu" signal)
		(10 "In4.Cu" signal)
		(12 "In5.Cu" signal)
		(14 "In6.Cu" signal)
		(2 "B.Cu" signal)
		(9 "F.Adhes" user "F.Adhesive")
		(11 "B.Adhes" user "B.Adhesive")
		(13 "F.Paste" user)
		(15 "B.Paste" user)
		(5 "F.SilkS" user "F.Silkscreen")
		(7 "B.SilkS" user "B.Silkscreen")
		(1 "F.Mask" user)
		(3 "B.Mask" user)
		(17 "Dwgs.User" user "User.Drawings")
		(19 "Cmts.User" user "User.Comments")
		(21 "Eco1.User" user "User.Eco1")
		(23 "Eco2.User" user "User.Eco2")
		(25 "Edge.Cuts" user)
		(27 "Margin" user)
		(31 "F.CrtYd" user "F.Courtyard")
		(29 "B.CrtYd" user "B.Courtyard")
		(35 "F.Fab" user)
		(33 "B.Fab" user)
	)
	(footprint "antmicro-footprints:C_0402_1005Metric"
		(layer "B.Cu")
		(at 78.55 97.4 90)
		(descr "Capacitor SMD 0402")
		(tags "capacitor SMD 0402")
		(property "Reference" "C135"
			(at 1.02 -0.28 90)
			(layer "B.SilkS")
			(effects
				(font
					(size 0.7 0.7)
					(thickness 0.15)
				)
				(justify right top mirror)
			)
		)
		(property "Value" "C_1u_25V_0402"
			(at -1.022927 -2.155213 90)
			(layer "B.Fab")
			(hide yes)
			(effects
				(font
					(size 0.7 0.7)
					(thickness 0.15)
				)
				(justify right top mirror)
			)
		)
		(property "Datasheet" "https://www.murata.com/products/productdetail?partno=GRM155R61E105KE11%23"
			(at 0 0 90)
			(layer "B.Fab")
			(hide yes)
			(effects
				(font
					(size 1.27 1.27)
					(thickness 0.15)
				)
				(justify mirror)
			)
		)
		(property "Description" "SMD Multilayer Ceramic Capacitor, 1 µF, 25 V, 0402 [1005 Metric], ± 10%, X5R, GRM Series"
			(at 0 0 90)
			(layer "B.Fab")
			(hide yes)
			(effects
				(font
					(size 1.27 1.27)
					(thickness 0.15)
				)
				(justify mirror)
			)
		)
		(property "MPN" "GRM155R61E105KE11J"
			(at 0 0 90)
			(unlocked yes)
			(layer "B.Fab")
			(hide yes)
			(effects
				(font
					(size 1 1)
					(thickness 0.15)
				)
				(justify mirror)
			)
		)
		(property "Manufacturer" "Murata"
			(at 0 0 90)
			(unlocked yes)
			(layer "B.Fab")
			(hide yes)
			(effects
				(font
					(size 1 1)
					(thickness 0.15)
				)
				(justify mirror)
			)
		)
		(property "License" "Apache-2.0"
			(at 0 0 90)
			(unlocked yes)
			(layer "B.Fab")
			(hide yes)
			(effects
				(font
					(size 1 1)
					(thickness 0.15)
				)
				(justify mirror)
			)
		)
		(property "Author" "Antmicro"
			(at 0 0 90)
			(unlocked yes)
			(layer "B.Fab")
			(hide yes)
			(effects
				(font
					(size 1 1)
					(thickness 0.15)
				)
				(justify mirror)
			)
		)
		(property "Val" "1u"
			(at 0 0 90)
			(unlocked yes)
			(layer "B.Fab")
			(hide yes)
			(effects
				(font
					(size 1 1)
					(thickness 0.15)
				)
				(justify mirror)
			)
		)
		(property "Voltage" "25V"
			(at 0 0 90)
			(unlocked yes)
			(layer "B.Fab")
			(hide yes)
			(effects
				(font
					(size 1 1)
					(thickness 0.15)
				)
				(justify mirror)
			)
		)
		(property "Dielectric" "X5R"
			(at 0 0 90)
			(unlocked yes)
			(layer "B.Fab")
			(hide yes)
			(effects
				(font
					(size 1 1)
					(thickness 0.15)
				)
				(justify mirror)
			)
		)
		(sheetname "/X710-AT2 power/")
		(sheetfile "x710-at2-power.kicad_sch")
		(attr smd)
		(fp_rect
			(start -0.925 0.47)
			(end 0.925 -0.47)
			(stroke
				(width 0.05)
				(type default)
			)
			(fill no)
			(layer "B.CrtYd")
		)
		(fp_line
			(start 0.504 -0.248)
			(end -0.494 -0.248)
			(stroke
				(width 0.15)
				(type solid)
			)
			(layer "B.Fab")
		)
		(fp_line
			(start -0.494 -0.248)
			(end -0.494 0.25)
			(stroke
				(width 0.15)
				(type solid)
			)
			(layer "B.Fab")
		)
		(fp_line
			(start 0.504 0.25)
			(end 0.504 -0.248)
			(stroke
				(width 0.15)
				(type solid)
			)
			(layer "B.Fab")
		)
		(fp_line
			(start -0.494 0.25)
			(end 0.504 0.25)
			(stroke
				(width 0.15)
				(type solid)
			)
			(layer "B.Fab")
		)
		(pad "1" smd roundrect
			(at -0.48 0 90)
			(size 0.59 0.64)
			(layers "B.Cu" "B.Mask" "B.Paste")
			(roundrect_rratio 0.25)
			(net 28 "GND")
			(pintype "passive")
		)
		(pad "2" smd roundrect
			(at 0.48 0 90)
			(size 0.59 0.64)
			(layers "B.Cu" "B.Mask" "B.Paste")
			(roundrect_rratio 0.25)
			(net 7 "+3V3")
			(pintype "passive")
		)
	)
	(footprint "antmicro-footprints:TP_SMD_0.75mm"
		(layer "B.Cu")
		(at 103.55 101.2 90)
		(property "Reference" "TP5"
			(at 0.265351 0.625533 180)
			(layer "B.SilkS")
			(effects
				(font
					(size 0.7 0.7)
					(thickness 0.15)
				)
				(justify right top mirror)
			)
		)
		(property "Value" "TP_0.75mm_SMD"
			(at 0 -1.2 90)
			(layer "B.Fab")
			(hide yes)
			(effects
				(font
					(size 0.7 0.7)
					(thickness 0.15)
				)
				(justify right top mirror)
			)
		)
		(property "Description" "SMT test point"
			(at 0 0 90)
			(layer "B.Fab")
			(hide yes)
			(effects
				(font
					(size 1.27 1.27)
					(thickness 0.15)
				)
				(justify mirror)
			)
		)
		(property "MPN" ""
			(at 0 0 90)
			(unlocked yes)
			(layer "B.Fab")
			(hide yes)
			(effects
				(font
					(size 1 1)
					(thickness 0.15)
				)
				(justify mirror)
			)
		)
		(property "Manufacturer" ""
			(at 0 0 90)
			(unlocked yes)
			(layer "B.Fab")
			(hide yes)
			(effects
				(font
					(size 1 1)
					(thickness 0.15)
				)
				(justify mirror)
			)
		)
		(property "Author" "Antmicro"
			(at 0 0 90)
			(unlocked yes)
			(layer "B.Fab")
			(hide yes)
			(effects
				(font
					(size 1 1)
					(thickness 0.15)
				)
				(justify mirror)
			)
		)
		(property "License" "Apache-2.0"
			(at 0 0 90)
			(unlocked yes)
			(layer "B.Fab")
			(hide yes)
			(effects
				(font
					(size 1 1)
					(thickness 0.15)
				)
				(justify mirror)
			)
		)
		(sheetname "/X710-AT2 Misc/")
		(sheetfile "x710-at2-mics.kicad_sch")
		(attr exclude_from_pos_files exclude_from_bom)
		(fp_circle
			(center 0 0)
			(end 0.475 0)
			(stroke
				(width 0.05)
				(type default)
			)
			(fill no)
			(layer "B.CrtYd")
		)
		(pad "1" smd circle
			(at 0 0 90)
			(size 0.75 0.75)
			(layers "B.Cu" "B.Mask")
			(net 366 "/X710-AT2 Misc/NCSI.TX_EN")
			(pinfunction "1")
			(pintype "passive")
		)
	)
	(footprint "antmicro-footprints:L_0402_1005Metric"
		(layer "B.Cu")
		(at 81.95 130.4 180)
		(descr "Inductor SMD 0402")
		(tags "Inductor SMD 0402")
		(property "Reference" "L6"
			(at -0.72 -3.35 0)
			(layer "B.SilkS")
			(effects
				(font
					(size 0.7 0.7)
					(thickness 0.15)
				)
				(justify left bottom mirror)
			)
		)
		(property "Value" "L_2n4_0.85A_0402"
			(at 0 -1.399999 0)
			(layer "B.Fab")
			(hide yes)
			(effects
				(font
					(size 0.7 0.7)
					(thickness 0.15)
				)
				(justify left bottom mirror)
			)
		)
		(property "Datasheet" "https://www.murata.com/products/productdetail?partno=LQW15AN2N4B00%23"
			(at 0 0 0)
			(layer "B.Fab")
			(hide yes)
			(effects
				(font
					(size 1.27 1.27)
					(thickness 0.15)
				)
				(justify mirror)
			)
		)
		(property "Description" "Wirewound Inductor, 2.4 nH, 0.05 ohm, 15 GHz, 850 mA, 0402 [1005 Metric], LQW15AN"
			(at 0 0 0)
			(layer "B.Fab")
			(hide yes)
			(effects
				(font
					(size 1.27 1.27)
					(thickness 0.15)
				)
				(justify mirror)
			)
		)
		(property "Val" "2n4/0.85A"
			(at 0 0 180)
			(unlocked yes)
			(layer "B.Fab")
			(hide yes)
			(effects
				(font
					(size 1 1)
					(thickness 0.15)
				)
				(justify mirror)
			)
		)
		(property "Manufacturer" "Murata"
			(at 0 0 180)
			(unlocked yes)
			(layer "B.Fab")
			(hide yes)
			(effects
				(font
					(size 1 1)
					(thickness 0.15)
				)
				(justify mirror)
			)
		)
		(property "MPN" "LQW15AN2N4B00D"
			(at 0 0 180)
			(unlocked yes)
			(layer "B.Fab")
			(hide yes)
			(effects
				(font
					(size 1 1)
					(thickness 0.15)
				)
				(justify mirror)
			)
		)
		(property "ISat" "0.85 A"
			(at 0 0 180)
			(unlocked yes)
			(layer "B.Fab")
			(hide yes)
			(effects
				(font
					(size 1 1)
					(thickness 0.15)
				)
				(justify mirror)
			)
		)
		(property "IMax" "0.85 A"
			(at 0 0 180)
			(unlocked yes)
			(layer "B.Fab")
			(hide yes)
			(effects
				(font
					(size 1 1)
					(thickness 0.15)
				)
				(justify mirror)
			)
		)
		(property "Size" "1.0x0.5"
			(at 0 0 180)
			(unlocked yes)
			(layer "B.Fab")
			(hide yes)
			(effects
				(font
					(size 1 1)
					(thickness 0.15)
				)
				(justify mirror)
			)
		)
		(property "Author" "Antmicro"
			(at 0 0 180)
			(unlocked yes)
			(layer "B.Fab")
			(hide yes)
			(effects
				(font
					(size 1 1)
					(thickness 0.15)
				)
				(justify mirror)
			)
		)
		(property "License" "Apache-2.0"
			(at 0 0 180)
			(unlocked yes)
			(layer "B.Fab")
			(hide yes)
			(effects
				(font
					(size 1 1)
					(thickness 0.15)
				)
				(justify mirror)
			)
		)
		(sheetname "/2xRJ45/")
		(sheetfile "2xrj45.kicad_sch")
		(attr smd)
		(fp_rect
			(start -0.925 0.47)
			(end 0.925 -0.47)
			(stroke
				(width 0.05)
				(type default)
			)
			(fill no)
			(layer "B.CrtYd")
		)
		(fp_rect
			(start -0.499 0.249)
			(end 0.499 -0.249)
			(stroke
				(width 0.15)
				(type solid)
			)
			(fill no)
			(layer "B.Fab")
		)
		(pad "1" smd roundrect
			(at -0.48 0 180)
			(size 0.59 0.64)
			(layers "B.Cu" "B.Mask" "B.Paste")
			(roundrect_rratio 0.25)
			(net 301 "+1V88_CT")
			(pintype "passive")
		)
		(pad "2" smd roundrect
			(at 0.48 0 180)
			(size 0.59 0.64)
			(layers "B.Cu" "B.Mask" "B.Paste")
			(roundrect_rratio 0.25)
			(net 299 "/2xRJ45/P0_CT")
			(pintype "passive")
		)
	)
	(footprint "antmicro-footprints:TP_SMD_1mm"
		(layer "B.Cu")
		(at 75.74 72.3 -90)
		(property "Reference" "TP31"
			(at -1.83 4.508102 90)
			(layer "B.SilkS")
			(effects
				(font
					(size 0.7 0.7)
					(thickness 0.15)
				)
				(justify left bottom mirror)
			)
		)
		(property "Value" "TP_1mm_SMD"
			(at 0 -1.4 90)
			(layer "B.Fab")
			(hide yes)
			(effects
				(font
					(size 0.7 0.7)
					(thickness 0.15)
				)
				(justify left bottom mirror)
			)
		)
		(property "Description" "Test point 1mm SMD"
			(at 0 0 90)
			(layer "B.Fab")
			(hide yes)
			(effects
				(font
					(size 1.27 1.27)
					(thickness 0.15)
				)
				(justify mirror)
			)
		)
		(property "MPN" ""
			(at 0 0 90)
			(unlocked yes)
			(layer "B.Fab")
			(hide yes)
			(effects
				(font
					(size 1 1)
					(thickness 0.15)
				)
				(justify mirror)
			)
		)
		(property "Manufacturer" ""
			(at 0 0 90)
			(unlocked yes)
			(layer "B.Fab")
			(hide yes)
			(effects
				(font
					(size 1 1)
					(thickness 0.15)
				)
				(justify mirror)
			)
		)
		(property "Author" "Antmicro"
			(at 0 0 90)
			(unlocked yes)
			(layer "B.Fab")
			(hide yes)
			(effects
				(font
					(size 1 1)
					(thickness 0.15)
				)
				(justify mirror)
			)
		)
		(property "License" "Apache-2.0"
			(at 0 0 90)
			(unlocked yes)
			(layer "B.Fab")
			(hide yes)
			(effects
				(font
					(size 1 1)
					(thickness 0.15)
				)
				(justify mirror)
			)
		)
		(sheetname "/Power/")
		(sheetfile "power.kicad_sch")
		(attr exclude_from_pos_files exclude_from_bom)
		(fp_circle
			(center 0 0)
			(end 0.6 0)
			(stroke
				(width 0.05)
				(type default)
			)
			(fill no)
			(layer "B.CrtYd")
		)
		(pad "1" smd circle
			(at 0 0 270)
			(size 1 1)
			(layers "B.Cu" "B.Mask")
			(net 9 "VCCD")
			(pinfunction "1")
			(pintype "passive")
		)
	)
	(footprint "antmicro-footprints:R_0402_1005Metric"
		(layer "B.Cu")
		(at 91 111.15 -90)
		(descr "Resistor SMD 0402")
		(tags "resistor SMD 0402")
		(property "Reference" "R111"
			(at 0.84 -0.36 90)
			(layer "B.SilkS")
			(effects
				(font
					(size 0.7 0.7)
					(thickness 0.15)
				)
				(justify left bottom mirror)
			)
		)
		(property "Value" "R_1k_0402"
			(at -1.011843 -1.772046 90)
			(layer "B.Fab")
			(hide yes)
			(effects
				(font
					(size 0.7 0.7)
					(thickness 0.15)
				)
				(justify left bottom mirror)
			)
		)
		(property "Datasheet" "https://www.bourns.com/docs/product-datasheets/cr.pdf"
			(at 0 0 90)
			(layer "B.Fab")
			(hide yes)
			(effects
				(font
					(size 1.27 1.27)
					(thickness 0.15)
				)
				(justify mirror)
			)
		)
		(property "Description" "SMD Chip Resistor, 1 kohm, ± 1%, 63 mW, 0402 [1005 Metric], Thick Film, General Purpose"
			(at 0 0 90)
			(layer "B.Fab")
			(hide yes)
			(effects
				(font
					(size 1.27 1.27)
					(thickness 0.15)
				)
				(justify mirror)
			)
		)
		(property "MPN" "CR0402-FX-1001GLF"
			(at 0 0 270)
			(unlocked yes)
			(layer "B.Fab")
			(hide yes)
			(effects
				(font
					(size 1 1)
					(thickness 0.15)
				)
				(justify mirror)
			)
		)
		(property "Manufacturer" "Bourns"
			(at 0 0 270)
			(unlocked yes)
			(layer "B.Fab")
			(hide yes)
			(effects
				(font
					(size 1 1)
					(thickness 0.15)
				)
				(justify mirror)
			)
		)
		(property "License" "Apache-2.0"
			(at 0 0 270)
			(unlocked yes)
			(layer "B.Fab")
			(hide yes)
			(effects
				(font
					(size 1 1)
					(thickness 0.15)
				)
				(justify mirror)
			)
		)
		(property "Author" "Antmicro"
			(at 0 0 270)
			(unlocked yes)
			(layer "B.Fab")
			(hide yes)
			(effects
				(font
					(size 1 1)
					(thickness 0.15)
				)
				(justify mirror)
			)
		)
		(property "Val" "1k"
			(at 0 0 270)
			(unlocked yes)
			(layer "B.Fab")
			(hide yes)
			(effects
				(font
					(size 1 1)
					(thickness 0.15)
				)
				(justify mirror)
			)
		)
		(property "Tolerance" "1%"
			(at 0 0 270)
			(unlocked yes)
			(layer "B.Fab")
			(hide yes)
			(effects
				(font
					(size 1 1)
					(thickness 0.15)
				)
				(justify mirror)
			)
		)
		(sheetname "/X710-AT2 Misc/")
		(sheetfile "x710-at2-mics.kicad_sch")
		(attr smd)
		(fp_rect
			(start -0.925 0.47)
			(end 0.925 -0.47)
			(stroke
				(width 0.05)
				(type default)
			)
			(fill no)
			(layer "B.CrtYd")
		)
		(fp_rect
			(start -0.5 0.25)
			(end 0.5 -0.25)
			(stroke
				(width 0.15)
				(type solid)
			)
			(fill no)
			(layer "B.Fab")
		)
		(pad "1" smd roundrect
			(at -0.48 0 270)
			(size 0.59 0.64)
			(layers "B.Cu" "B.Mask" "B.Paste")
			(roundrect_rratio 0.25)
			(net 142 "/X710-AT2 10GbE/~{P0_INT}")
			(pintype "passive")
		)
		(pad "2" smd roundrect
			(at 0.48 0 270)
			(size 0.59 0.64)
			(layers "B.Cu" "B.Mask" "B.Paste")
			(roundrect_rratio 0.25)
			(net 7 "+3V3")
			(pintype "passive")
		)
	)
	(footprint "antmicro-footprints:C_0402_1005Metric"
		(layer "B.Cu")
		(at 81.95 131.4 180)
		(descr "Capacitor SMD 0402")
		(tags "capacitor SMD 0402")
		(property "Reference" "C59"
			(at -0.721 -3.350999 0)
			(layer "B.SilkS")
			(effects
				(font
					(size 0.7 0.7)
					(thickness 0.15)
				)
				(justify left bottom mirror)
			)
		)
		(property "Value" "C_1u_25V_0402"
			(at -1.022927 -2.155213 0)
			(layer "B.Fab")
			(hide yes)
			(effects
				(font
					(size 0.7 0.7)
					(thickness 0.15)
				)
				(justify left bottom mirror)
			)
		)
		(property "Datasheet" "https://www.murata.com/products/productdetail?partno=GRM155R61E105KE11%23"
			(at 0 0 0)
			(layer "B.Fab")
			(hide yes)
			(effects
				(font
					(size 1.27 1.27)
					(thickness 0.15)
				)
				(justify mirror)
			)
		)
		(property "Description" "SMD Multilayer Ceramic Capacitor, 1 µF, 25 V, 0402 [1005 Metric], ± 10%, X5R, GRM Series"
			(at 0 0 0)
			(layer "B.Fab")
			(hide yes)
			(effects
				(font
					(size 1.27 1.27)
					(thickness 0.15)
				)
				(justify mirror)
			)
		)
		(property "MPN" "GRM155R61E105KE11J"
			(at 0 0 180)
			(unlocked yes)
			(layer "B.Fab")
			(hide yes)
			(effects
				(font
					(size 1 1)
					(thickness 0.15)
				)
				(justify mirror)
			)
		)
		(property "Manufacturer" "Murata"
			(at 0 0 180)
			(unlocked yes)
			(layer "B.Fab")
			(hide yes)
			(effects
				(font
					(size 1 1)
					(thickness 0.15)
				)
				(justify mirror)
			)
		)
		(property "License" "Apache-2.0"
			(at 0 0 180)
			(unlocked yes)
			(layer "B.Fab")
			(hide yes)
			(effects
				(font
					(size 1 1)
					(thickness 0.15)
				)
				(justify mirror)
			)
		)
		(property "Author" "Antmicro"
			(at 0 0 180)
			(unlocked yes)
			(layer "B.Fab")
			(hide yes)
			(effects
				(font
					(size 1 1)
					(thickness 0.15)
				)
				(justify mirror)
			)
		)
		(property "Val" "1u"
			(at 0 0 180)
			(unlocked yes)
			(layer "B.Fab")
			(hide yes)
			(effects
				(font
					(size 1 1)
					(thickness 0.15)
				)
				(justify mirror)
			)
		)
		(property "Voltage" "25V"
			(at 0 0 180)
			(unlocked yes)
			(layer "B.Fab")
			(hide yes)
			(effects
				(font
					(size 1 1)
					(thickness 0.15)
				)
				(justify mirror)
			)
		)
		(property "Dielectric" "X5R"
			(at 0 0 180)
			(unlocked yes)
			(layer "B.Fab")
			(hide yes)
			(effects
				(font
					(size 1 1)
					(thickness 0.15)
				)
				(justify mirror)
			)
		)
		(sheetname "/2xRJ45/")
		(sheetfile "2xrj45.kicad_sch")
		(attr smd)
		(fp_rect
			(start -0.925 0.47)
			(end 0.925 -0.47)
			(stroke
				(width 0.05)
				(type default)
			)
			(fill no)
			(layer "B.CrtYd")
		)
		(fp_line
			(start 0.504 0.25)
			(end 0.504 -0.248)
			(stroke
				(width 0.15)
				(type solid)
			)
			(layer "B.Fab")
		)
		(fp_line
			(start 0.504 -0.248)
			(end -0.494 -0.248)
			(stroke
				(width 0.15)
				(type solid)
			)
			(layer "B.Fab")
		)
		(fp_line
			(start -0.494 0.25)
			(end 0.504 0.25)
			(stroke
				(width 0.15)
				(type solid)
			)
			(layer "B.Fab")
		)
		(fp_line
			(start -0.494 -0.248)
			(end -0.494 0.25)
			(stroke
				(width 0.15)
				(type solid)
			)
			(layer "B.Fab")
		)
		(pad "1" smd roundrect
			(at -0.48 0 180)
			(size 0.59 0.64)
			(layers "B.Cu" "B.Mask" "B.Paste")
			(roundrect_rratio 0.25)
			(net 28 "GND")
			(pintype "passive")
		)
		(pad "2" smd roundrect
			(at 0.48 0 180)
			(size 0.59 0.64)
			(layers "B.Cu" "B.Mask" "B.Paste")
			(roundrect_rratio 0.25)
			(net 299 "/2xRJ45/P0_CT")
			(pintype "passive")
		)
	)
)
